# T6G (Grand Teton) — schematic netlist excerpt (pin names and nets, part order shuffled) for the footprints in the layout excerpt that follows; sources: Cadence DE-HDL packaged netlist, KiCad conversion of 04192023_DAF0TMB3IC0_F0TG_MB_C_brd_V02_OCP.brd

C984  Q_CAP  0.1UF 10V 10% X7S  pkg C0201  page 301 : A = P0V9_CPU0_RT2_2A ; B = GND
PC564_3  Q_CAP  22UF 4V 20% X6S  pkg C0805  page 195 : A = PVDDCR_CPU0_P0 ; B = GND
C6553  Q_CAP_DIFFBUS  DIFF BUS_0.22UF 6.3V 20% X6S  pkg C0201  page 286 : \1\ = P5E_CPU0_P1_TX_BUF_C_DP<10> ; \2\ = P5E_CPU0_P1_TX_BUF_DP<10>
PC91_1  Q_CAP  22UF 16V 20% X6S  pkg C0805  page 201 : A = SW_P12V_AUX_PVDDCR_CPU1_P0_FLT ; B = GND

(kicad_pcb
	(version 20260206)
	(generator "pcbnew")
	(generator_version "10.0")
	(general
		(thickness 1.6)
		(legacy_teardrops no)
	)
	(paper "A4")
	(title_block
		(title "04192023_DAF0TMB3IC0_F0TG_MB_C_brd_V02_OCP.brd")
		(comment 1 "Grand Teton / footprints 8128-8131 of 8354")
	)
	(layers
		(0 "F.Cu" signal "TOP")
		(4 "In1.Cu" signal "GND")
		(6 "In2.Cu" signal "IN1")
		(8 "In3.Cu" signal "GND1")
		(10 "In4.Cu" signal "IN2")
		(12 "In5.Cu" signal "GND2")
		(14 "In6.Cu" signal "IN3")
		(16 "In7.Cu" signal "GND3")
		(18 "In8.Cu" signal "VCC")
		(20 "In9.Cu" signal "VCC1")
		(22 "In10.Cu" signal "GND4")
		(24 "In11.Cu" signal "IN4")
		(26 "In12.Cu" signal "GND5")
		(28 "In13.Cu" signal "IN5")
		(30 "In14.Cu" signal "GND6")
		(32 "In15.Cu" signal "IN6")
		(34 "In16.Cu" signal "GND7")
		(2 "B.Cu" signal "BOTTOM")
		(9 "F.Adhes" user "F.Adhesive")
		(11 "B.Adhes" user "B.Adhesive")
		(13 "F.Paste" user "Package Geometry/Pastemask Top")
		(15 "B.Paste" user "Package Geometry/Pastemask Bottom")
		(5 "F.SilkS" user "Ref Des/Silkscreen Top")
		(7 "B.SilkS" user "Ref Des/Silkscreen Bottom")
		(1 "F.Mask" user "Board Geometry/Soldermask Top")
		(3 "B.Mask" user "Board Geometry/Soldermask Bottom")
		(17 "Dwgs.User" user "User.Drawings")
		(19 "Cmts.User" user "User.Comments")
		(21 "Eco1.User" user "User.Eco1")
		(23 "Eco2.User" user "User.Eco2")
		(25 "Edge.Cuts" user "Board Geometry/Outline")
		(27 "Margin" user)
		(31 "F.CrtYd" user "Package Geometry/Place Bound Top")
		(29 "B.CrtYd" user "Package Geometry/Place Bound Bottom")
		(35 "F.Fab" user "Ref Des/Assembly Top")
		(33 "B.Fab" user "Ref Des/Assembly Bottom")
	)
	(footprint ""
		(layer "B.Cu")
		(at 338.308696 -335.041494 90)
		(property "Reference" "PC91_1"
			(at 0 0 90)
			(layer "B.SilkS")
			(hide yes)
			(effects
				(font
					(size 1.27 1.27)
				)
				(justify mirror)
			)
		)
		(property "Value" ""
			(at 0 0 90)
			(layer "B.Fab")
			(effects
				(font
					(size 1.27 1.27)
				)
				(justify mirror)
			)
		)
		(duplicate_pad_numbers_are_jumpers no)
		(fp_line
			(start 1.524 -0.762)
			(end -1.524 -0.762)
			(stroke
				(width 0.1524)
				(type default)
			)
			(layer "B.SilkS")
		)
		(fp_line
			(start -1.524 -0.762)
			(end -1.524 0.762)
			(stroke
				(width 0.1524)
				(type default)
			)
			(layer "B.SilkS")
		)
		(fp_line
			(start 1.524 0.762)
			(end 1.524 -0.762)
			(stroke
				(width 0.1524)
				(type default)
			)
			(layer "B.SilkS")
		)
		(fp_line
			(start -1.524 0.762)
			(end 1.524 0.762)
			(stroke
				(width 0.1524)
				(type default)
			)
			(layer "B.SilkS")
		)
		(fp_line
			(start 1.1049 -0.724916)
			(end 1.1049 0.724916)
			(stroke
				(width 0.1)
				(type default)
			)
			(layer "B.Fab")
		)
		(fp_line
			(start -1.1049 -0.724916)
			(end 1.1049 -0.724916)
			(stroke
				(width 0.1)
				(type default)
			)
			(layer "B.Fab")
		)
		(fp_line
			(start 1.1049 0.724916)
			(end -1.1049 0.724916)
			(stroke
				(width 0.1)
				(type default)
			)
			(layer "B.Fab")
		)
		(fp_line
			(start -1.1049 0.724916)
			(end -1.1049 -0.724916)
			(stroke
				(width 0.1)
				(type default)
			)
			(layer "B.Fab")
		)
		(pad "1" smd rect
			(at 0.889 0 90)
			(size 1.016 1.27)
			(layers "B.Cu" "B.Mask" "B.Paste")
			(net "SW_P12V_AUX_PVDDCR_CPU1_P0_FLT")
		)
		(pad "2" smd rect
			(at -0.889 0 90)
			(size 1.016 1.27)
			(layers "B.Cu" "B.Mask" "B.Paste")
			(net "GND")
		)
	)
	(footprint ""
		(layer "B.Cu")
		(at 419.946328 -396.393162 -90)
		(property "Reference" "C984"
			(at 0 0 90)
			(layer "B.SilkS")
			(hide yes)
			(effects
				(font
					(size 1.27 1.27)
				)
				(justify mirror)
			)
		)
		(property "Value" ""
			(at 0 0 90)
			(layer "B.Fab")
			(effects
				(font
					(size 1.27 1.27)
				)
				(justify mirror)
			)
		)
		(duplicate_pad_numbers_are_jumpers no)
		(fp_line
			(start -0.299974 0.150114)
			(end 0.299974 0.150114)
			(stroke
				(width 0.1)
				(type default)
			)
			(layer "B.Fab")
		)
		(fp_line
			(start 0.299974 0.150114)
			(end 0.299974 -0.150114)
			(stroke
				(width 0.1)
				(type default)
			)
			(layer "B.Fab")
		)
		(fp_line
			(start -0.299974 -0.150114)
			(end -0.299974 0.150114)
			(stroke
				(width 0.1)
				(type default)
			)
			(layer "B.Fab")
		)
		(fp_line
			(start 0.299974 -0.150114)
			(end -0.299974 -0.150114)
			(stroke
				(width 0.1)
				(type default)
			)
			(layer "B.Fab")
		)
		(pad "1" smd rect
			(at 0.2667 0 90)
			(size 0.3048 0.381)
			(layers "B.Cu" "B.Mask" "B.Paste")
			(net "P0V9_CPU0_RT2_2A")
		)
		(pad "2" smd rect
			(at -0.2667 0 90)
			(size 0.3048 0.381)
			(layers "B.Cu" "B.Mask" "B.Paste")
			(net "GND")
		)
	)
	(footprint ""
		(layer "B.Cu")
		(at 376.6566 -191.24676 90)
		(property "Reference" "PC564_3"
			(at 0 0 90)
			(layer "B.SilkS")
			(hide yes)
			(effects
				(font
					(size 1.27 1.27)
				)
				(justify mirror)
			)
		)
		(property "Value" ""
			(at 0 0 90)
			(layer "B.Fab")
			(effects
				(font
					(size 1.27 1.27)
				)
				(justify mirror)
			)
		)
		(duplicate_pad_numbers_are_jumpers no)
		(fp_line
			(start 1.524 -0.762)
			(end -1.524 -0.762)
			(stroke
				(width 0.1524)
				(type default)
			)
			(layer "B.SilkS")
		)
		(fp_line
			(start -1.524 -0.762)
			(end -1.524 0.762)
			(stroke
				(width 0.1524)
				(type default)
			)
			(layer "B.SilkS")
		)
		(fp_line
			(start 1.524 0.762)
			(end 1.524 -0.762)
			(stroke
				(width 0.1524)
				(type default)
			)
			(layer "B.SilkS")
		)
		(fp_line
			(start -1.524 0.762)
			(end 1.524 0.762)
			(stroke
				(width 0.1524)
				(type default)
			)
			(layer "B.SilkS")
		)
		(fp_line
			(start 1.1049 -0.724916)
			(end 1.1049 0.724916)
			(stroke
				(width 0.1)
				(type default)
			)
			(layer "B.Fab")
		)
		(fp_line
			(start -1.1049 -0.724916)
			(end 1.1049 -0.724916)
			(stroke
				(width 0.1)
				(type default)
			)
			(layer "B.Fab")
		)
		(fp_line
			(start 1.1049 0.724916)
			(end -1.1049 0.724916)
			(stroke
				(width 0.1)
				(type default)
			)
			(layer "B.Fab")
		)
		(fp_line
			(start -1.1049 0.724916)
			(end -1.1049 -0.724916)
			(stroke
				(width 0.1)
				(type default)
			)
			(layer "B.Fab")
		)
		(pad "1" smd rect
			(at 0.889 0 90)
			(size 1.016 1.27)
			(layers "B.Cu" "B.Mask" "B.Paste")
			(net "PVDDCR_CPU0_P0")
		)
		(pad "2" smd rect
			(at -0.889 0 90)
			(size 1.016 1.27)
			(layers "B.Cu" "B.Mask" "B.Paste")
			(net "GND")
		)
	)
	(footprint ""
		(layer "B.Cu")
		(at 336.846926 -416.899344 90)
		(property "Reference" "C6553"
			(at 0 0 90)
			(layer "B.SilkS")
			(hide yes)
			(effects
				(font
					(size 1.27 1.27)
				)
				(justify mirror)
			)
		)
		(property "Value" ""
			(at 0 0 90)
			(layer "B.Fab")
			(effects
				(font
					(size 1.27 1.27)
				)
				(justify mirror)
			)
		)
		(duplicate_pad_numbers_are_jumpers no)
		(fp_line
			(start 0.299974 -0.150114)
			(end -0.299974 -0.150114)
			(stroke
				(width 0.1)
				(type default)
			)
			(layer "B.Fab")
		)
		(fp_line
			(start -0.299974 -0.150114)
			(end -0.299974 0.150114)
			(stroke
				(width 0.1)
				(type default)
			)
			(layer "B.Fab")
		)
		(fp_line
			(start 0.299974 0.150114)
			(end 0.299974 -0.150114)
			(stroke
				(width 0.1)
				(type default)
			)
			(layer "B.Fab")
		)
		(fp_line
			(start -0.299974 0.150114)
			(end 0.299974 0.150114)
			(stroke
				(width 0.1)
				(type default)
			)
			(layer "B.Fab")
		)
		(pad "1" smd rect
			(at 0.2667 0 270)
			(size 0.3048 0.381)
			(layers "B.Cu" "B.Mask" "B.Paste")
			(net "P5E_CPU0_P1_TX_BUF_C_DP<10>")
		)
		(pad "2" smd rect
			(at -0.2667 0 270)
			(size 0.3048 0.381)
			(layers "B.Cu" "B.Mask" "B.Paste")
			(net "P5E_CPU0_P1_TX_BUF_DP<10>")
		)
	)
)
